(kicad_pcb
	(version 20260206)
	(generator "pcbnew")
	(generator_version "10.0")
	(general
		(thickness 1.6)
		(legacy_teardrops no)
	)
	(paper "A4")
	(title_block
		(title "04192023_DAF0TMB3IC0_F0TG_MB_C_brd_V02_OCP.brd")
		(comment 1 "Grand Teton / footprints 6020-6026 of 8354")
	)
	(layers
		(0 "F.Cu" signal "TOP")
		(4 "In1.Cu" signal "GND")
		(6 "In2.Cu" signal "IN1")
		(8 "In3.Cu" signal "GND1")
		(10 "In4.Cu" signal "IN2")
		(12 "In5.Cu" signal "GND2")
		(14 "In6.Cu" signal "IN3")
		(16 "In7.Cu" signal "GND3")
		(18 "In8.Cu" signal "VCC")
		(20 "In9.Cu" signal "VCC1")
		(22 "In10.Cu" signal "GND4")
		(24 "In11.Cu" signal "IN4")
		(26 "In12.Cu" signal "GND5")
		(28 "In13.Cu" signal "IN5")
		(30 "In14.Cu" signal "GND6")
		(32 "In15.Cu" signal "IN6")
		(34 "In16.Cu" signal "GND7")
		(2 "B.Cu" signal "BOTTOM")
		(9 "F.Adhes" user "F.Adhesive")
		(11 "B.Adhes" user "B.Adhesive")
		(13 "F.Paste" user "Package Geometry/Pastemask Top")
		(15 "B.Paste" user "Package Geometry/Pastemask Bottom")
		(5 "F.SilkS" user "Ref Des/Silkscreen Top")
		(7 "B.SilkS" user "Ref Des/Silkscreen Bottom")
		(1 "F.Mask" user "Board Geometry/Soldermask Top")
		(3 "B.Mask" user "Board Geometry/Soldermask Bottom")
		(17 "Dwgs.User" user "User.Drawings")
		(19 "Cmts.User" user "User.Comments")
		(21 "Eco1.User" user "User.Eco1")
		(23 "Eco2.User" user "User.Eco2")
		(25 "Edge.Cuts" user "Board Geometry/Outline")
		(27 "Margin" user)
		(31 "F.CrtYd" user "Package Geometry/Place Bound Top")
		(29 "B.CrtYd" user "Package Geometry/Place Bound Bottom")
		(35 "F.Fab" user "Ref Des/Assembly Top")
		(33 "B.Fab" user "Ref Des/Assembly Bottom")
	)
	(footprint ""
		(layer "B.Cu")
		(at 130.702304 -33.019492 -90)
		(property "Reference" "C6065"
			(at 0 0 90)
			(layer "B.SilkS")
			(hide yes)
			(effects
				(font
					(size 1.27 1.27)
				)
				(justify mirror)
			)
		)
		(property "Value" ""
			(at 0 0 90)
			(layer "B.Fab")
			(effects
				(font
					(size 1.27 1.27)
				)
				(justify mirror)
			)
		)
		(duplicate_pad_numbers_are_jumpers no)
		(fp_line
			(start -0.7874 0.4064)
			(end 0.7874 0.4064)
			(stroke
				(width 0.1524)
				(type default)
			)
			(layer "B.SilkS")
		)
		(fp_line
			(start 0.7874 0.4064)
			(end 0.7874 -0.4064)
			(stroke
				(width 0.1524)
				(type default)
			)
			(layer "B.SilkS")
		)
		(fp_line
			(start -0.7874 -0.4064)
			(end -0.7874 0.4064)
			(stroke
				(width 0.1524)
				(type default)
			)
			(layer "B.SilkS")
		)
		(fp_line
			(start 0.7874 -0.4064)
			(end -0.7874 -0.4064)
			(stroke
				(width 0.1524)
				(type default)
			)
			(layer "B.SilkS")
		)
		(fp_line
			(start -0.67945 0.3048)
			(end -0.120396 0.3048)
			(stroke
				(width 0.1)
				(type default)
			)
			(layer "B.Fab")
		)
		(fp_line
			(start -0.120396 0.3048)
			(end -0.120396 0.2794)
			(stroke
				(width 0.1)
				(type default)
			)
			(layer "B.Fab")
		)
		(fp_line
			(start 0.12065 0.3048)
			(end 0.67945 0.3048)
			(stroke
				(width 0.1)
				(type default)
			)
			(layer "B.Fab")
		)
		(fp_line
			(start 0.67945 0.3048)
			(end 0.67945 -0.305054)
			(stroke
				(width 0.1)
				(type default)
			)
			(layer "B.Fab")
		)
		(fp_line
			(start -0.120396 0.2794)
			(end 0.12065 0.2794)
			(stroke
				(width 0.1)
				(type default)
			)
			(layer "B.Fab")
		)
		(fp_line
			(start 0.12065 0.2794)
			(end 0.12065 0.3048)
			(stroke
				(width 0.1)
				(type default)
			)
			(layer "B.Fab")
		)
		(fp_line
			(start -0.12065 -0.2794)
			(end -0.12065 -0.3048)
			(stroke
				(width 0.1)
				(type default)
			)
			(layer "B.Fab")
		)
		(fp_line
			(start 0.12065 -0.2794)
			(end -0.12065 -0.2794)
			(stroke
				(width 0.1)
				(type default)
			)
			(layer "B.Fab")
		)
		(fp_line
			(start -0.67945 -0.3048)
			(end -0.67945 0.3048)
			(stroke
				(width 0.1)
				(type default)
			)
			(layer "B.Fab")
		)
		(fp_line
			(start -0.12065 -0.3048)
			(end -0.67945 -0.3048)
			(stroke
				(width 0.1)
				(type default)
			)
			(layer "B.Fab")
		)
		(fp_line
			(start 0.12065 -0.305054)
			(end 0.12065 -0.2794)
			(stroke
				(width 0.1)
				(type default)
			)
			(layer "B.Fab")
		)
		(fp_line
			(start 0.67945 -0.305054)
			(end 0.12065 -0.305054)
			(stroke
				(width 0.1)
				(type default)
			)
			(layer "B.Fab")
		)
		(pad "1" smd circle
			(at 0.40005 0 90)
			(size 0 0)
			(layers "B.Cu" "B.Mask" "B.Paste")
			(net "P1V2_AUX")
		)
		(pad "2" smd circle
			(at -0.40005 0 90)
			(size 0 0)
			(layers "B.Cu" "B.Mask" "B.Paste")
			(net "GND")
		)
	)
	(footprint ""
		(layer "B.Cu")
		(at 235.660692 -422.849548 90)
		(property "Reference" "R2802"
			(at 0 0 90)
			(layer "B.SilkS")
			(hide yes)
			(effects
				(font
					(size 1.27 1.27)
				)
				(justify mirror)
			)
		)
		(property "Value" ""
			(at 0 0 90)
			(layer "B.Fab")
			(effects
				(font
					(size 1.27 1.27)
				)
				(justify mirror)
			)
		)
		(duplicate_pad_numbers_are_jumpers no)
		(fp_line
			(start 0.7874 -0.4064)
			(end -0.7874 -0.4064)
			(stroke
				(width 0.1524)
				(type default)
			)
			(layer "B.SilkS")
		)
		(fp_line
			(start -0.7874 -0.4064)
			(end -0.7874 0.4064)
			(stroke
				(width 0.1524)
				(type default)
			)
			(layer "B.SilkS")
		)
		(fp_line
			(start 0.7874 0.4064)
			(end 0.7874 -0.4064)
			(stroke
				(width 0.1524)
				(type default)
			)
			(layer "B.SilkS")
		)
		(fp_line
			(start -0.7874 0.4064)
			(end 0.7874 0.4064)
			(stroke
				(width 0.1524)
				(type default)
			)
			(layer "B.SilkS")
		)
		(fp_line
			(start 0.67945 -0.305054)
			(end 0.12065 -0.305054)
			(stroke
				(width 0.1)
				(type default)
			)
			(layer "B.Fab")
		)
		(fp_line
			(start 0.12065 -0.305054)
			(end 0.12065 -0.2794)
			(stroke
				(width 0.1)
				(type default)
			)
			(layer "B.Fab")
		)
		(fp_line
			(start -0.12065 -0.3048)
			(end -0.67945 -0.3048)
			(stroke
				(width 0.1)
				(type default)
			)
			(layer "B.Fab")
		)
		(fp_line
			(start -0.67945 -0.3048)
			(end -0.67945 0.3048)
			(stroke
				(width 0.1)
				(type default)
			)
			(layer "B.Fab")
		)
		(fp_line
			(start 0.12065 -0.2794)
			(end -0.12065 -0.2794)
			(stroke
				(width 0.1)
				(type default)
			)
			(layer "B.Fab")
		)
		(fp_line
			(start -0.12065 -0.2794)
			(end -0.12065 -0.3048)
			(stroke
				(width 0.1)
				(type default)
			)
			(layer "B.Fab")
		)
		(fp_line
			(start 0.12065 0.2794)
			(end 0.12065 0.3048)
			(stroke
				(width 0.1)
				(type default)
			)
			(layer "B.Fab")
		)
		(fp_line
			(start -0.120396 0.2794)
			(end 0.12065 0.2794)
			(stroke
				(width 0.1)
				(type default)
			)
			(layer "B.Fab")
		)
		(fp_line
			(start 0.67945 0.3048)
			(end 0.67945 -0.305054)
			(stroke
				(width 0.1)
				(type default)
			)
			(layer "B.Fab")
		)
		(fp_line
			(start 0.12065 0.3048)
			(end 0.67945 0.3048)
			(stroke
				(width 0.1)
				(type default)
			)
			(layer "B.Fab")
		)
		(fp_line
			(start -0.120396 0.3048)
			(end -0.120396 0.2794)
			(stroke
				(width 0.1)
				(type default)
			)
			(layer "B.Fab")
		)
		(fp_line
			(start -0.67945 0.3048)
			(end -0.120396 0.3048)
			(stroke
				(width 0.1)
				(type default)
			)
			(layer "B.Fab")
		)
		(pad "1" smd circle
			(at 0.40005 0 270)
			(size 0 0)
			(layers "B.Cu" "B.Mask" "B.Paste")
			(net "HPDB_HSC_PWRGD_R")
		)
		(pad "2" smd circle
			(at -0.40005 0 270)
			(size 0 0)
			(layers "B.Cu" "B.Mask" "B.Paste")
			(net "HPDB_HSC_PWRGD")
		)
	)
	(footprint ""
		(layer "B.Cu")
		(at 356.406958 -246.376952)
		(property "Reference" "C2199"
			(at 0 0 0)
			(layer "B.SilkS")
			(hide yes)
			(effects
				(font
					(size 1.27 1.27)
				)
				(justify mirror)
			)
		)
		(property "Value" ""
			(at 0 0 0)
			(layer "B.Fab")
			(effects
				(font
					(size 1.27 1.27)
				)
				(justify mirror)
			)
		)
		(duplicate_pad_numbers_are_jumpers no)
		(fp_line
			(start -0.7874 -0.4064)
			(end -0.7874 0.4064)
			(stroke
				(width 0.1524)
				(type default)
			)
			(layer "B.SilkS")
		)
		(fp_line
			(start -0.7874 0.4064)
			(end 0.7874 0.4064)
			(stroke
				(width 0.1524)
				(type default)
			)
			(layer "B.SilkS")
		)
		(fp_line
			(start 0.7874 -0.4064)
			(end -0.7874 -0.4064)
			(stroke
				(width 0.1524)
				(type default)
			)
			(layer "B.SilkS")
		)
		(fp_line
			(start 0.7874 0.4064)
			(end 0.7874 -0.4064)
			(stroke
				(width 0.1524)
				(type default)
			)
			(layer "B.SilkS")
		)
		(fp_line
			(start -0.67945 -0.3048)
			(end -0.67945 0.3048)
			(stroke
				(width 0.1)
				(type default)
			)
			(layer "B.Fab")
		)
		(fp_line
			(start -0.67945 0.3048)
			(end -0.120396 0.3048)
			(stroke
				(width 0.1)
				(type default)
			)
			(layer "B.Fab")
		)
		(fp_line
			(start -0.12065 -0.3048)
			(end -0.67945 -0.3048)
			(stroke
				(width 0.1)
				(type default)
			)
			(layer "B.Fab")
		)
		(fp_line
			(start -0.12065 -0.2794)
			(end -0.12065 -0.3048)
			(stroke
				(width 0.1)
				(type default)
			)
			(layer "B.Fab")
		)
		(fp_line
			(start -0.120396 0.2794)
			(end 0.12065 0.2794)
			(stroke
				(width 0.1)
				(type default)
			)
			(layer "B.Fab")
		)
		(fp_line
			(start -0.120396 0.3048)
			(end -0.120396 0.2794)
			(stroke
				(width 0.1)
				(type default)
			)
			(layer "B.Fab")
		)
		(fp_line
			(start 0.12065 -0.305054)
			(end 0.12065 -0.2794)
			(stroke
				(width 0.1)
				(type default)
			)
			(layer "B.Fab")
		)
		(fp_line
			(start 0.12065 -0.2794)
			(end -0.12065 -0.2794)
			(stroke
				(width 0.1)
				(type default)
			)
			(layer "B.Fab")
		)
		(fp_line
			(start 0.12065 0.2794)
			(end 0.12065 0.3048)
			(stroke
				(width 0.1)
				(type default)
			)
			(layer "B.Fab")
		)
		(fp_line
			(start 0.12065 0.3048)
			(end 0.67945 0.3048)
			(stroke
				(width 0.1)
				(type default)
			)
			(layer "B.Fab")
		)
		(fp_line
			(start 0.67945 -0.305054)
			(end 0.12065 -0.305054)
			(stroke
				(width 0.1)
				(type default)
			)
			(layer "B.Fab")
		)
		(fp_line
			(start 0.67945 0.3048)
			(end 0.67945 -0.305054)
			(stroke
				(width 0.1)
				(type default)
			)
			(layer "B.Fab")
		)
		(pad "1" smd circle
			(at 0.40005 0 180)
			(size 0 0)
			(layers "B.Cu" "B.Mask" "B.Paste")
			(net "PVDDCR_CPU0_P0")
		)
		(pad "2" smd circle
			(at -0.40005 0 180)
			(size 0 0)
			(layers "B.Cu" "B.Mask" "B.Paste")
			(net "GND")
		)
	)
	(footprint ""
		(layer "B.Cu")
		(at 386.21843 -396.393162 -90)
		(property "Reference" "C1051"
			(at 0 0 90)
			(layer "B.SilkS")
			(hide yes)
			(effects
				(font
					(size 1.27 1.27)
				)
				(justify mirror)
			)
		)
		(property "Value" ""
			(at 0 0 90)
			(layer "B.Fab")
			(effects
				(font
					(size 1.27 1.27)
				)
				(justify mirror)
			)
		)
		(duplicate_pad_numbers_are_jumpers no)
		(fp_line
			(start -0.299974 0.150114)
			(end 0.299974 0.150114)
			(stroke
				(width 0.1)
				(type default)
			)
			(layer "B.Fab")
		)
		(fp_line
			(start 0.299974 0.150114)
			(end 0.299974 -0.150114)
			(stroke
				(width 0.1)
				(type default)
			)
			(layer "B.Fab")
		)
		(fp_line
			(start -0.299974 -0.150114)
			(end -0.299974 0.150114)
			(stroke
				(width 0.1)
				(type default)
			)
			(layer "B.Fab")
		)
		(fp_line
			(start 0.299974 -0.150114)
			(end -0.299974 -0.150114)
			(stroke
				(width 0.1)
				(type default)
			)
			(layer "B.Fab")
		)
		(pad "1" smd rect
			(at 0.2667 0 90)
			(size 0.3048 0.381)
			(layers "B.Cu" "B.Mask" "B.Paste")
			(net "P0V9_CPU0_RT3_2A")
		)
		(pad "2" smd rect
			(at -0.2667 0 90)
			(size 0.3048 0.381)
			(layers "B.Cu" "B.Mask" "B.Paste")
			(net "GND")
		)
	)
	(footprint ""
		(layer "B.Cu")
		(at 233.172 -340.868 180)
		(property "Reference" "R976"
			(at 0 0 0)
			(layer "B.SilkS")
			(hide yes)
			(effects
				(font
					(size 1.27 1.27)
				)
				(justify mirror)
			)
		)
		(property "Value" ""
			(at 0 0 0)
			(layer "B.Fab")
			(effects
				(font
					(size 1.27 1.27)
				)
				(justify mirror)
			)
		)
		(duplicate_pad_numbers_are_jumpers no)
		(fp_line
			(start 0.32512 0.175006)
			(end 0.32512 -0.175006)
			(stroke
				(width 0.1)
				(type default)
			)
			(layer "B.Fab")
		)
		(fp_line
			(start 0.32512 -0.175006)
			(end -0.32512 -0.175006)
			(stroke
				(width 0.1)
				(type default)
			)
			(layer "B.Fab")
		)
		(fp_line
			(start -0.32512 0.175006)
			(end 0.32512 0.175006)
			(stroke
				(width 0.1)
				(type default)
			)
			(layer "B.Fab")
		)
		(fp_line
			(start -0.32512 -0.175006)
			(end -0.32512 0.175006)
			(stroke
				(width 0.1)
				(type default)
			)
			(layer "B.Fab")
		)
		(pad "1" smd rect
			(at 0.2667 0)
			(size 0.3048 0.381)
			(layers "B.Cu" "B.Mask" "B.Paste")
			(net "SMB_RT_CPU0_P0_R_SCL")
		)
		(pad "2" smd rect
			(at -0.2667 0 180)
			(size 0.3048 0.381)
			(layers "B.Cu" "B.Mask" "B.Paste")
			(net "SMB_RT_CPU0_P0_R2_SCL")
		)
	)
	(footprint ""
		(layer "B.Cu")
		(at 348.818454 -267.52931)
		(property "Reference" "C2231"
			(at 0 0 0)
			(layer "B.SilkS")
			(hide yes)
			(effects
				(font
					(size 1.27 1.27)
				)
				(justify mirror)
			)
		)
		(property "Value" ""
			(at 0 0 0)
			(layer "B.Fab")
			(effects
				(font
					(size 1.27 1.27)
				)
				(justify mirror)
			)
		)
		(duplicate_pad_numbers_are_jumpers no)
		(fp_line
			(start -0.7874 -0.4064)
			(end -0.7874 0.4064)
			(stroke
				(width 0.1524)
				(type default)
			)
			(layer "B.SilkS")
		)
		(fp_line
			(start -0.7874 0.4064)
			(end 0.7874 0.4064)
			(stroke
				(width 0.1524)
				(type default)
			)
			(layer "B.SilkS")
		)
		(fp_line
			(start 0.7874 -0.4064)
			(end -0.7874 -0.4064)
			(stroke
				(width 0.1524)
				(type default)
			)
			(layer "B.SilkS")
		)
		(fp_line
			(start 0.7874 0.4064)
			(end 0.7874 -0.4064)
			(stroke
				(width 0.1524)
				(type default)
			)
			(layer "B.SilkS")
		)
		(fp_line
			(start -0.67945 -0.3048)
			(end -0.67945 0.3048)
			(stroke
				(width 0.1)
				(type default)
			)
			(layer "B.Fab")
		)
		(fp_line
			(start -0.67945 0.3048)
			(end -0.120396 0.3048)
			(stroke
				(width 0.1)
				(type default)
			)
			(layer "B.Fab")
		)
		(fp_line
			(start -0.12065 -0.3048)
			(end -0.67945 -0.3048)
			(stroke
				(width 0.1)
				(type default)
			)
			(layer "B.Fab")
		)
		(fp_line
			(start -0.12065 -0.2794)
			(end -0.12065 -0.3048)
			(stroke
				(width 0.1)
				(type default)
			)
			(layer "B.Fab")
		)
		(fp_line
			(start -0.120396 0.2794)
			(end 0.12065 0.2794)
			(stroke
				(width 0.1)
				(type default)
			)
			(layer "B.Fab")
		)
		(fp_line
			(start -0.120396 0.3048)
			(end -0.120396 0.2794)
			(stroke
				(width 0.1)
				(type default)
			)
			(layer "B.Fab")
		)
		(fp_line
			(start 0.12065 -0.305054)
			(end 0.12065 -0.2794)
			(stroke
				(width 0.1)
				(type default)
			)
			(layer "B.Fab")
		)
		(fp_line
			(start 0.12065 -0.2794)
			(end -0.12065 -0.2794)
			(stroke
				(width 0.1)
				(type default)
			)
			(layer "B.Fab")
		)
		(fp_line
			(start 0.12065 0.2794)
			(end 0.12065 0.3048)
			(stroke
				(width 0.1)
				(type default)
			)
			(layer "B.Fab")
		)
		(fp_line
			(start 0.12065 0.3048)
			(end 0.67945 0.3048)
			(stroke
				(width 0.1)
				(type default)
			)
			(layer "B.Fab")
		)
		(fp_line
			(start 0.67945 -0.305054)
			(end 0.12065 -0.305054)
			(stroke
				(width 0.1)
				(type default)
			)
			(layer "B.Fab")
		)
		(fp_line
			(start 0.67945 0.3048)
			(end 0.67945 -0.305054)
			(stroke
				(width 0.1)
				(type default)
			)
			(layer "B.Fab")
		)
		(pad "1" smd circle
			(at 0.40005 0 180)
			(size 0 0)
			(layers "B.Cu" "B.Mask" "B.Paste")
			(net "PVDDCR_CPU1_P0")
		)
		(pad "2" smd circle
			(at -0.40005 0 180)
			(size 0 0)
			(layers "B.Cu" "B.Mask" "B.Paste")
			(net "GND")
		)
	)
	(footprint ""
		(layer "B.Cu")
		(at 180.166518 -415.616644 90)
		(property "Reference" "R2927"
			(at 0 0 90)
			(layer "B.SilkS")
			(hide yes)
			(effects
				(font
					(size 1.27 1.27)
				)
				(justify mirror)
			)
		)
		(property "Value" ""
			(at 0 0 90)
			(layer "B.Fab")
			(effects
				(font
					(size 1.27 1.27)
				)
				(justify mirror)
			)
		)
		(duplicate_pad_numbers_are_jumpers no)
		(fp_line
			(start 0.7874 -0.4064)
			(end -0.7874 -0.4064)
			(stroke
				(width 0.1524)
				(type default)
			)
			(layer "B.SilkS")
		)
		(fp_line
			(start -0.7874 -0.4064)
			(end -0.7874 0.4064)
			(stroke
				(width 0.1524)
				(type default)
			)
			(layer "B.SilkS")
		)
		(fp_line
			(start 0.7874 0.4064)
			(end 0.7874 -0.4064)
			(stroke
				(width 0.1524)
				(type default)
			)
			(layer "B.SilkS")
		)
		(fp_line
			(start -0.7874 0.4064)
			(end 0.7874 0.4064)
			(stroke
				(width 0.1524)
				(type default)
			)
			(layer "B.SilkS")
		)
		(fp_line
			(start 0.67945 -0.305054)
			(end 0.12065 -0.305054)
			(stroke
				(width 0.1)
				(type default)
			)
			(layer "B.Fab")
		)
		(fp_line
			(start 0.12065 -0.305054)
			(end 0.12065 -0.2794)
			(stroke
				(width 0.1)
				(type default)
			)
			(layer "B.Fab")
		)
		(fp_line
			(start -0.12065 -0.3048)
			(end -0.67945 -0.3048)
			(stroke
				(width 0.1)
				(type default)
			)
			(layer "B.Fab")
		)
		(fp_line
			(start -0.67945 -0.3048)
			(end -0.67945 0.3048)
			(stroke
				(width 0.1)
				(type default)
			)
			(layer "B.Fab")
		)
		(fp_line
			(start 0.12065 -0.2794)
			(end -0.12065 -0.2794)
			(stroke
				(width 0.1)
				(type default)
			)
			(layer "B.Fab")
		)
		(fp_line
			(start -0.12065 -0.2794)
			(end -0.12065 -0.3048)
			(stroke
				(width 0.1)
				(type default)
			)
			(layer "B.Fab")
		)
		(fp_line
			(start 0.12065 0.2794)
			(end 0.12065 0.3048)
			(stroke
				(width 0.1)
				(type default)
			)
			(layer "B.Fab")
		)
		(fp_line
			(start -0.120396 0.2794)
			(end 0.12065 0.2794)
			(stroke
				(width 0.1)
				(type default)
			)
			(layer "B.Fab")
		)
		(fp_line
			(start 0.67945 0.3048)
			(end 0.67945 -0.305054)
			(stroke
				(width 0.1)
				(type default)
			)
			(layer "B.Fab")
		)
		(fp_line
			(start 0.12065 0.3048)
			(end 0.67945 0.3048)
			(stroke
				(width 0.1)
				(type default)
			)
			(layer "B.Fab")
		)
		(fp_line
			(start -0.120396 0.3048)
			(end -0.120396 0.2794)
			(stroke
				(width 0.1)
				(type default)
			)
			(layer "B.Fab")
		)
		(fp_line
			(start -0.67945 0.3048)
			(end -0.120396 0.3048)
			(stroke
				(width 0.1)
				(type default)
			)
			(layer "B.Fab")
		)
		(pad "1" smd circle
			(at 0.40005 0 270)
			(size 0 0)
			(layers "B.Cu" "B.Mask" "B.Paste")
			(net "RST_SWB_BIC_BUF_R_N")
		)
		(pad "2" smd circle
			(at -0.40005 0 270)
			(size 0 0)
			(layers "B.Cu" "B.Mask" "B.Paste")
			(net "GND")
		)
	)
)
